(kicad_pcb
	(version 20241229)
	(generator "pcbnew")
	(generator_version "9.0")
	(general
		(thickness 1.62)
		(legacy_teardrops no)
	)
	(paper "A3")
	(title_block
		(title "COM Express 7 Baseboard")
		(date "2025-02-04")
		(rev "1.1.2")
		(company "Antmicro Ltd")
		(comment 1 "www.antmicro.com")
		(comment 9 "footprints 519-524 of 802")
	)
	(layers
		(0 "F.Cu" signal)
		(4 "In1.Cu" signal)
		(6 "In2.Cu" signal)
		(8 "In3.Cu" signal)
		(10 "In4.Cu" signal)
		(12 "In5.Cu" signal)
		(14 "In6.Cu" signal)
		(2 "B.Cu" signal)
		(9 "F.Adhes" user "F.Adhesive")
		(11 "B.Adhes" user "B.Adhesive")
		(13 "F.Paste" user)
		(15 "B.Paste" user)
		(5 "F.SilkS" user "F.Silkscreen")
		(7 "B.SilkS" user "B.Silkscreen")
		(1 "F.Mask" user)
		(3 "B.Mask" user)
		(17 "Dwgs.User" user "User.Drawings")
		(19 "Cmts.User" user "User.Comments")
		(21 "Eco1.User" user "User.Eco1")
		(23 "Eco2.User" user "User.Eco2")
		(25 "Edge.Cuts" user)
		(27 "Margin" user)
		(31 "F.CrtYd" user "F.Courtyard")
		(29 "B.CrtYd" user "B.Courtyard")
		(35 "F.Fab" user)
		(33 "B.Fab" user)
	)
	(footprint "antmicro-footprints:R_0805_2012Metric"
		(layer "F.Cu")
		(at 304.25 116.43 180)
		(property "Reference" "R103"
			(at -1.4 -1.88 0)
			(layer "F.SilkS")
			(effects
				(font
					(size 0.7 0.7)
					(thickness 0.15)
				)
				(justify right bottom)
			)
		)
		(property "Value" "R_0R001_0805"
			(at 0 1.8 0)
			(layer "F.Fab")
			(effects
				(font
					(size 0.7 0.7)
					(thickness 0.15)
				)
				(justify right bottom)
			)
		)
		(property "Datasheet" "https://www.eaton.com/content/dam/eaton/products/electronic-components/resources/data-sheet/eaton-msma-automotive-smd-current-sense-resistor-metal-strip-data-sheet-elx1179.pdf"
			(at 0 0 180)
			(layer "F.Fab")
			(hide yes)
			(effects
				(font
					(size 1.27 1.27)
					(thickness 0.15)
				)
			)
		)
		(property "Author" "Antmicro"
			(at 608.5 232.86 0)
			(layer "F.Fab")
			(hide yes)
			(effects
				(font
					(size 1 1)
					(thickness 0.15)
				)
			)
		)
		(property "License" "Apache-2.0"
			(at 608.5 232.86 0)
			(layer "F.Fab")
			(hide yes)
			(effects
				(font
					(size 1 1)
					(thickness 0.15)
				)
			)
		)
		(property "MPN" "MSMA0805R0010FSM"
			(at 608.5 232.86 0)
			(layer "F.Fab")
			(hide yes)
			(effects
				(font
					(size 1 1)
					(thickness 0.15)
				)
			)
		)
		(property "Manufacturer" "Eaton"
			(at 608.5 232.86 0)
			(layer "F.Fab")
			(hide yes)
			(effects
				(font
					(size 1 1)
					(thickness 0.15)
				)
			)
		)
		(property "Public" "False"
			(at 608.5 232.86 0)
			(layer "F.Fab")
			(hide yes)
			(effects
				(font
					(size 1 1)
					(thickness 0.15)
				)
			)
		)
		(property "Tolerance" "1%"
			(at 608.5 232.86 0)
			(layer "F.Fab")
			(hide yes)
			(effects
				(font
					(size 1 1)
					(thickness 0.15)
				)
			)
		)
		(property "Val" "0R001"
			(at 608.5 232.86 0)
			(layer "F.Fab")
			(hide yes)
			(effects
				(font
					(size 1 1)
					(thickness 0.15)
				)
			)
		)
		(sheetname "Power")
		(sheetfile "power.kicad_sch")
		(attr smd)
		(fp_line
			(start -0.3 -0.701)
			(end 0.298 -0.701)
			(stroke
				(width 0.15)
				(type solid)
			)
			(layer "F.SilkS")
		)
		(fp_line
			(start -0.32 0.699)
			(end 0.28 0.699)
			(stroke
				(width 0.15)
				(type solid)
			)
			(layer "F.SilkS")
		)
		(fp_rect
			(start 1.95 -0.9)
			(end -1.95 0.9)
			(stroke
				(width 0.05)
				(type default)
			)
			(fill no)
			(layer "F.CrtYd")
		)
		(fp_line
			(start 0.949 -0.677)
			(end 0.949 0.675)
			(stroke
				(width 0.15)
				(type solid)
			)
			(layer "F.Fab")
		)
		(fp_line
			(start -0.951 0.68)
			(end 0.949 0.68)
			(stroke
				(width 0.15)
				(type solid)
			)
			(layer "F.Fab")
		)
		(fp_line
			(start -0.951 -0.677)
			(end -0.951 0.675)
			(stroke
				(width 0.15)
				(type solid)
			)
			(layer "F.Fab")
		)
		(fp_line
			(start -0.951 -0.682)
			(end 0.949 -0.682)
			(stroke
				(width 0.15)
				(type solid)
			)
			(layer "F.Fab")
		)
		(pad "1" smd roundrect
			(at -1.1 0 180)
			(size 1.2 1.3)
			(layers "F.Cu" "F.Mask" "F.Paste")
			(roundrect_rratio 0.25)
			(net 70 "Net-(C49-Pad2)")
			(pintype "passive")
			(teardrops
				(best_length_ratio 0.2)
				(max_length 1)
				(best_width_ratio 0.9)
				(max_width 2)
				(curved_edges yes)
				(filter_ratio 0.9)
				(enabled yes)
				(allow_two_segments yes)
				(prefer_zone_connections yes)
			)
		)
		(pad "2" smd roundrect
			(at 1.1 0 180)
			(size 1.2 1.3)
			(layers "F.Cu" "F.Mask" "F.Paste")
			(roundrect_rratio 0.25)
			(net 74 "+1V0")
			(pintype "passive")
			(teardrops
				(best_length_ratio 0.2)
				(max_length 1)
				(best_width_ratio 0.9)
				(max_width 2)
				(curved_edges yes)
				(filter_ratio 0.9)
				(enabled yes)
				(allow_two_segments yes)
				(prefer_zone_connections yes)
			)
		)
	)
	(footprint "antmicro-footprints:TP_SMD_0.75mm"
		(layer "F.Cu")
		(at 116.134999 78.9 90)
		(property "Reference" "TP9"
			(at -2.46 0.415001 90)
			(layer "F.SilkS")
			(effects
				(font
					(size 0.7 0.7)
					(thickness 0.15)
				)
				(justify left bottom)
			)
		)
		(property "Value" "TP_0.75mm_SMD"
			(at 0 1.2 90)
			(layer "F.Fab")
			(effects
				(font
					(size 0.7 0.7)
					(thickness 0.15)
				)
				(justify left bottom)
			)
		)
		(property "Author" "Antmicro"
			(at 195.034999 -37.234999 0)
			(layer "F.Fab")
			(hide yes)
			(effects
				(font
					(size 1 1)
					(thickness 0.15)
				)
			)
		)
		(property "License" "Apache-2.0"
			(at 195.034999 -37.234999 0)
			(layer "F.Fab")
			(hide yes)
			(effects
				(font
					(size 1 1)
					(thickness 0.15)
				)
			)
		)
		(property "MPN" ""
			(at 195.034999 -37.234999 0)
			(layer "F.Fab")
			(hide yes)
			(effects
				(font
					(size 1 1)
					(thickness 0.15)
				)
			)
		)
		(property "Manufacturer" ""
			(at 195.034999 -37.234999 0)
			(layer "F.Fab")
			(hide yes)
			(effects
				(font
					(size 1 1)
					(thickness 0.15)
				)
			)
		)
		(property "Public" "False"
			(at 195.034999 -37.234999 0)
			(layer "F.Fab")
			(hide yes)
			(effects
				(font
					(size 1 1)
					(thickness 0.15)
				)
			)
		)
		(sheetname "USB-C console")
		(sheetfile "usb-c_console.kicad_sch")
		(attr exclude_from_pos_files exclude_from_bom)
		(fp_circle
			(center 0 0)
			(end 0.475 0)
			(stroke
				(width 0.05)
				(type default)
			)
			(fill no)
			(layer "F.CrtYd")
		)
		(pad "1" smd circle
			(at 0 0 90)
			(size 0.75 0.75)
			(layers "F.Cu" "F.Mask")
			(net 701 "/USB-C console/FTDI_CBUS0")
			(pinfunction "1")
			(pintype "passive")
			(teardrops
				(best_length_ratio 0.4)
				(max_length 1)
				(best_width_ratio 0.9)
				(max_width 2)
				(curved_edges yes)
				(filter_ratio 0.9)
				(enabled yes)
				(allow_two_segments yes)
				(prefer_zone_connections yes)
			)
		)
	)
	(footprint "antmicro-footprints:C_0402_1005Metric"
		(layer "F.Cu")
		(at 308.7 118.71 180)
		(descr "Capacitor SMD 0402")
		(tags "capacitor SMD 0402")
		(property "Reference" "C49"
			(at 0.85 -0.45 0)
			(layer "F.SilkS")
			(effects
				(font
					(size 0.7 0.7)
					(thickness 0.15)
				)
				(justify right bottom)
			)
		)
		(property "Value" "C_1u_0402"
			(at -1.022927 2.155213 0)
			(layer "F.Fab")
			(effects
				(font
					(size 0.7 0.7)
					(thickness 0.15)
				)
				(justify right bottom)
			)
		)
		(property "Datasheet" "https://product.tdk.com/en/search/capacitor/ceramic/mlcc/info?part_no=C1005X6S1A105K050BC"
			(at 0 0 180)
			(layer "F.Fab")
			(hide yes)
			(effects
				(font
					(size 1.27 1.27)
					(thickness 0.15)
				)
			)
		)
		(property "Author" "Antmicro"
			(at 617.4 237.42 0)
			(layer "F.Fab")
			(hide yes)
			(effects
				(font
					(size 1 1)
					(thickness 0.15)
				)
			)
		)
		(property "Dielectric" ""
			(at 617.4 237.42 0)
			(layer "F.Fab")
			(hide yes)
			(effects
				(font
					(size 1 1)
					(thickness 0.15)
				)
			)
		)
		(property "License" "Apache-2.0"
			(at 617.4 237.42 0)
			(layer "F.Fab")
			(hide yes)
			(effects
				(font
					(size 1 1)
					(thickness 0.15)
				)
			)
		)
		(property "MPN" "C1005X6S1A105K050BC"
			(at 617.4 237.42 0)
			(layer "F.Fab")
			(hide yes)
			(effects
				(font
					(size 1 1)
					(thickness 0.15)
				)
			)
		)
		(property "Manufacturer" "TDK"
			(at 617.4 237.42 0)
			(layer "F.Fab")
			(hide yes)
			(effects
				(font
					(size 1 1)
					(thickness 0.15)
				)
			)
		)
		(property "Public" "False"
			(at 617.4 237.42 0)
			(layer "F.Fab")
			(hide yes)
			(effects
				(font
					(size 1 1)
					(thickness 0.15)
				)
			)
		)
		(property "Val" "1u"
			(at 617.4 237.42 0)
			(layer "F.Fab")
			(hide yes)
			(effects
				(font
					(size 1 1)
					(thickness 0.15)
				)
			)
		)
		(property "Voltage" ""
			(at 617.4 237.42 0)
			(layer "F.Fab")
			(hide yes)
			(effects
				(font
					(size 1 1)
					(thickness 0.15)
				)
			)
		)
		(sheetname "Power")
		(sheetfile "power.kicad_sch")
		(attr smd)
		(fp_rect
			(start -0.925 -0.47)
			(end 0.925 0.47)
			(stroke
				(width 0.05)
				(type default)
			)
			(fill no)
			(layer "F.CrtYd")
		)
		(fp_line
			(start 0.504 0.248)
			(end -0.494 0.248)
			(stroke
				(width 0.15)
				(type solid)
			)
			(layer "F.Fab")
		)
		(fp_line
			(start 0.504 -0.25)
			(end 0.504 0.248)
			(stroke
				(width 0.15)
				(type solid)
			)
			(layer "F.Fab")
		)
		(fp_line
			(start -0.494 0.248)
			(end -0.494 -0.25)
			(stroke
				(width 0.15)
				(type solid)
			)
			(layer "F.Fab")
		)
		(fp_line
			(start -0.494 -0.25)
			(end 0.504 -0.25)
			(stroke
				(width 0.15)
				(type solid)
			)
			(layer "F.Fab")
		)
		(pad "1" smd roundrect
			(at -0.48 0 180)
			(size 0.59 0.64)
			(layers "F.Cu" "F.Mask" "F.Paste")
			(roundrect_rratio 0.25)
			(net 1 "GND")
			(pintype "passive")
			(teardrops
				(best_length_ratio 0.2)
				(max_length 1)
				(best_width_ratio 0.9)
				(max_width 2)
				(curved_edges yes)
				(filter_ratio 0.9)
				(enabled yes)
				(allow_two_segments yes)
				(prefer_zone_connections yes)
			)
		)
		(pad "2" smd roundrect
			(at 0.48 0 180)
			(size 0.59 0.64)
			(layers "F.Cu" "F.Mask" "F.Paste")
			(roundrect_rratio 0.25)
			(net 70 "Net-(C49-Pad2)")
			(pintype "passive")
			(teardrops
				(best_length_ratio 0.2)
				(max_length 1)
				(best_width_ratio 0.9)
				(max_width 2)
				(curved_edges yes)
				(filter_ratio 0.9)
				(enabled yes)
				(allow_two_segments yes)
				(prefer_zone_connections yes)
			)
		)
	)
	(footprint "antmicro-footprints:R_0402_1005Metric"
		(layer "F.Cu")
		(at 130.12 118.85 180)
		(descr "Resistor SMD 0402")
		(tags "resistor SMD 0402")
		(property "Reference" "R21"
			(at 0.781 0.42 0)
			(layer "F.SilkS")
			(effects
				(font
					(size 0.7 0.7)
					(thickness 0.15)
				)
				(justify right top)
			)
		)
		(property "Value" "R_0R_0402"
			(at -1.011843 1.772046 0)
			(layer "F.Fab")
			(effects
				(font
					(size 0.7 0.7)
					(thickness 0.15)
				)
				(justify right top)
			)
		)
		(property "Datasheet" "https://industrial.panasonic.com/cdbs/www-data/pdf/RDA0000/AOA0000C301.pdf"
			(at 0 0 0)
			(layer "F.Fab")
			(hide yes)
			(effects
				(font
					(size 1.27 1.27)
					(thickness 0.15)
				)
			)
		)
		(property "Author" "Antmicro"
			(at 358.37 -62.19 90)
			(layer "F.Fab")
			(hide yes)
			(effects
				(font
					(size 1 1)
					(thickness 0.15)
				)
			)
		)
		(property "Current" "1A"
			(at 358.37 -62.19 90)
			(layer "F.Fab")
			(hide yes)
			(effects
				(font
					(size 1 1)
					(thickness 0.15)
				)
			)
		)
		(property "License" "Apache-2.0"
			(at 358.37 -62.19 90)
			(layer "F.Fab")
			(hide yes)
			(effects
				(font
					(size 1 1)
					(thickness 0.15)
				)
			)
		)
		(property "MPN" "ERJ2GE0R00X"
			(at 358.37 -62.19 90)
			(layer "F.Fab")
			(hide yes)
			(effects
				(font
					(size 1 1)
					(thickness 0.15)
				)
			)
		)
		(property "Manufacturer" "Panasonic"
			(at 358.37 -62.19 90)
			(layer "F.Fab")
			(hide yes)
			(effects
				(font
					(size 1 1)
					(thickness 0.15)
				)
			)
		)
		(property "Public" "False"
			(at 358.37 -62.19 90)
			(layer "F.Fab")
			(hide yes)
			(effects
				(font
					(size 1 1)
					(thickness 0.15)
				)
			)
		)
		(property "Tolerance" ""
			(at 358.37 -62.19 90)
			(layer "F.Fab")
			(hide yes)
			(effects
				(font
					(size 1 1)
					(thickness 0.15)
				)
			)
		)
		(property "Val" "0R"
			(at 358.37 -62.19 90)
			(layer "F.Fab")
			(hide yes)
			(effects
				(font
					(size 1 1)
					(thickness 0.15)
				)
			)
		)
		(sheetname "2xUSB3.0+RJ45")
		(sheetfile "usb3+rj45.kicad_sch")
		(attr smd)
		(fp_rect
			(start -0.925 -0.47)
			(end 0.925 0.47)
			(stroke
				(width 0.05)
				(type default)
			)
			(fill no)
			(layer "F.CrtYd")
		)
		(fp_rect
			(start -0.5 -0.25)
			(end 0.5 0.25)
			(stroke
				(width 0.15)
				(type solid)
			)
			(fill no)
			(layer "F.Fab")
		)
		(pad "1" smd roundrect
			(at -0.48 0 180)
			(size 0.59 0.64)
			(layers "F.Cu" "F.Mask" "F.Paste")
			(roundrect_rratio 0.25)
			(net 312 "/2xUSB3.0+RJ45/USB_1.D-")
			(pintype "passive")
			(teardrops
				(best_length_ratio 0.2)
				(max_length 1)
				(best_width_ratio 0.9)
				(max_width 2)
				(curved_edges yes)
				(filter_ratio 0.9)
				(enabled yes)
				(allow_two_segments yes)
				(prefer_zone_connections yes)
			)
		)
		(pad "2" smd roundrect
			(at 0.48 0 180)
			(size 0.59 0.64)
			(layers "F.Cu" "F.Mask" "F.Paste")
			(roundrect_rratio 0.25)
			(net 123 "/2xUSB3.0+RJ45/P1_D-")
			(pintype "passive")
			(teardrops
				(best_length_ratio 0.2)
				(max_length 1)
				(best_width_ratio 0.9)
				(max_width 2)
				(curved_edges yes)
				(filter_ratio 0.9)
				(enabled yes)
				(allow_two_segments yes)
				(prefer_zone_connections yes)
			)
		)
	)
	(footprint "antmicro-footprints:R_0402_1005Metric"
		(layer "F.Cu")
		(at 240 78.5 -90)
		(descr "Resistor SMD 0402")
		(tags "resistor SMD 0402")
		(property "Reference" "R161"
			(at 1.1 0.4 90)
			(layer "F.SilkS")
			(effects
				(font
					(size 0.7 0.7)
					(thickness 0.15)
				)
				(justify right top)
			)
		)
		(property "Value" "R_5k1_0402"
			(at -4.236842 54.437047 90)
			(layer "F.Fab")
			(hide yes)
			(effects
				(font
					(size 0.7 0.7)
					(thickness 0.15)
				)
				(justify right top)
			)
		)
		(property "Datasheet" "https://www.bourns.com/docs/product-datasheets/cr.pdf"
			(at 0 0 90)
			(layer "F.Fab")
			(hide yes)
			(effects
				(font
					(size 1.27 1.27)
					(thickness 0.15)
				)
			)
		)
		(property "Author" "Antmicro"
			(at 0 0 90)
			(layer "F.Fab")
			(hide yes)
			(effects
				(font
					(size 1 1)
					(thickness 0.15)
				)
			)
		)
		(property "License" "Apache-2.0"
			(at 0 0 90)
			(layer "F.Fab")
			(hide yes)
			(effects
				(font
					(size 1 1)
					(thickness 0.15)
				)
			)
		)
		(property "MPN" "CR0402-FX-5101GLF"
			(at 0 0 90)
			(layer "F.Fab")
			(hide yes)
			(effects
				(font
					(size 1 1)
					(thickness 0.15)
				)
			)
		)
		(property "Manufacturer" "Bourns"
			(at 0 0 90)
			(layer "F.Fab")
			(hide yes)
			(effects
				(font
					(size 1 1)
					(thickness 0.15)
				)
			)
		)
		(property "Public" "False"
			(at 0 0 90)
			(layer "F.Fab")
			(hide yes)
			(effects
				(font
					(size 1 1)
					(thickness 0.15)
				)
			)
		)
		(property "Tolerance" "1%"
			(at 0 0 90)
			(layer "F.Fab")
			(hide yes)
			(effects
				(font
					(size 1 1)
					(thickness 0.15)
				)
			)
		)
		(property "Val" "5k1"
			(at 0 0 90)
			(layer "F.Fab")
			(hide yes)
			(effects
				(font
					(size 1 1)
					(thickness 0.15)
				)
			)
		)
		(sheetname "Com Express 7 MGMT")
		(sheetfile "com_express_7_mgmt.kicad_sch")
		(attr smd)
		(fp_rect
			(start -0.925 -0.47)
			(end 0.925 0.47)
			(stroke
				(width 0.05)
				(type default)
			)
			(fill no)
			(layer "F.CrtYd")
		)
		(fp_rect
			(start -0.5 -0.25)
			(end 0.5 0.25)
			(stroke
				(width 0.15)
				(type solid)
			)
			(fill no)
			(layer "F.Fab")
		)
		(pad "1" smd roundrect
			(at -0.48 0 270)
			(size 0.59 0.64)
			(layers "F.Cu" "F.Mask" "F.Paste")
			(roundrect_rratio 0.25)
			(net 400 "/Com Express 7 MGMT/FAN_PWM")
			(pintype "passive")
			(teardrops
				(best_length_ratio 0.2)
				(max_length 1)
				(best_width_ratio 0.9)
				(max_width 2)
				(curved_edges yes)
				(filter_ratio 0.9)
				(enabled yes)
				(allow_two_segments yes)
				(prefer_zone_connections yes)
			)
		)
		(pad "2" smd roundrect
			(at 0.48 0 270)
			(size 0.59 0.64)
			(layers "F.Cu" "F.Mask" "F.Paste")
			(roundrect_rratio 0.25)
			(net 2 "+3V3")
			(pintype "passive")
			(teardrops
				(best_length_ratio 0.2)
				(max_length 1)
				(best_width_ratio 0.9)
				(max_width 2)
				(curved_edges yes)
				(filter_ratio 0.9)
				(enabled yes)
				(allow_two_segments yes)
				(prefer_zone_connections yes)
			)
		)
	)
	(footprint "antmicro-footprints:C_0402_1005Metric"
		(layer "B.Cu")
		(at 213.11 127.121 180)
		(descr "Capacitor SMD 0402")
		(tags "capacitor SMD 0402")
		(property "Reference" "C108"
			(at -1.64 0.461 0)
			(layer "B.SilkS")
			(effects
				(font
					(size 0.7 0.7)
					(thickness 0.15)
				)
				(justify left bottom mirror)
			)
		)
		(property "Value" "C_100n_0402"
			(at -1.022927 -2.155213 0)
			(layer "B.Fab")
			(effects
				(font
					(size 0.7 0.7)
					(thickness 0.15)
				)
				(justify left bottom mirror)
			)
		)
		(property "Datasheet" "https://www.murata.com/products/productdetail?partno=GRM155R61H104KE14%23"
			(at 0 0 180)
			(layer "F.Fab")
			(hide yes)
			(effects
				(font
					(size 1.27 1.27)
					(thickness 0.15)
				)
			)
		)
		(property "Author" "Antmicro"
			(at 426.22 254.242 0)
			(layer "B.Fab")
			(hide yes)
			(effects
				(font
					(size 1 1)
					(thickness 0.15)
				)
				(justify mirror)
			)
		)
		(property "Dielectric" "X5R"
			(at 426.22 254.242 0)
			(layer "B.Fab")
			(hide yes)
			(effects
				(font
					(size 1 1)
					(thickness 0.15)
				)
				(justify mirror)
			)
		)
		(property "License" "Apache-2.0"
			(at 426.22 254.242 0)
			(layer "B.Fab")
			(hide yes)
			(effects
				(font
					(size 1 1)
					(thickness 0.15)
				)
				(justify mirror)
			)
		)
		(property "MPN" "GRM155R61H104KE14D"
			(at 426.22 254.242 0)
			(layer "B.Fab")
			(hide yes)
			(effects
				(font
					(size 1 1)
					(thickness 0.15)
				)
				(justify mirror)
			)
		)
		(property "Manufacturer" "Murata"
			(at 426.22 254.242 0)
			(layer "B.Fab")
			(hide yes)
			(effects
				(font
					(size 1 1)
					(thickness 0.15)
				)
				(justify mirror)
			)
		)
		(property "Public" "False"
			(at 426.22 254.242 0)
			(layer "B.Fab")
			(hide yes)
			(effects
				(font
					(size 1 1)
					(thickness 0.15)
				)
				(justify mirror)
			)
		)
		(property "Val" "100n"
			(at 426.22 254.242 0)
			(layer "B.Fab")
			(hide yes)
			(effects
				(font
					(size 1 1)
					(thickness 0.15)
				)
				(justify mirror)
			)
		)
		(property "Voltage" "50V"
			(at 426.22 254.242 0)
			(layer "B.Fab")
			(hide yes)
			(effects
				(font
					(size 1 1)
					(thickness 0.15)
				)
				(justify mirror)
			)
		)
		(sheetname "PCIe misc")
		(sheetfile "pcie_misc.kicad_sch")
		(attr smd)
		(fp_rect
			(start -0.925 0.47)
			(end 0.925 -0.47)
			(stroke
				(width 0.05)
				(type default)
			)
			(fill no)
			(layer "B.CrtYd")
		)
		(fp_line
			(start 0.504 0.25)
			(end -0.494 0.25)
			(stroke
				(width 0.15)
				(type solid)
			)
			(layer "B.Fab")
		)
		(fp_line
			(start 0.504 -0.248)
			(end 0.504 0.25)
			(stroke
				(width 0.15)
				(type solid)
			)
			(layer "B.Fab")
		)
		(fp_line
			(start -0.494 0.25)
			(end -0.494 -0.248)
			(stroke
				(width 0.15)
				(type solid)
			)
			(layer "B.Fab")
		)
		(fp_line
			(start -0.494 -0.248)
			(end 0.504 -0.248)
			(stroke
				(width 0.15)
				(type solid)
			)
			(layer "B.Fab")
		)
		(pad "1" smd roundrect
			(at -0.48 0 180)
			(size 0.59 0.64)
			(layers "B.Cu" "B.Mask" "B.Paste")
			(roundrect_rratio 0.25)
			(net 1 "GND")
			(pintype "passive")
			(teardrops
				(best_length_ratio 0.2)
				(max_length 1)
				(best_width_ratio 0.9)
				(max_width 2)
				(curved_edges yes)
				(filter_ratio 0.9)
				(enabled yes)
				(allow_two_segments yes)
				(prefer_zone_connections yes)
			)
		)
		(pad "2" smd roundrect
			(at 0.48 0 180)
			(size 0.59 0.64)
			(layers "B.Cu" "B.Mask" "B.Paste")
			(roundrect_rratio 0.25)
			(net 2 "+3V3")
			(pintype "passive")
			(teardrops
				(best_length_ratio 0.2)
				(max_length 1)
				(best_width_ratio 0.9)
				(max_width 2)
				(curved_edges yes)
				(filter_ratio 0.9)
				(enabled yes)
				(allow_two_segments yes)
				(prefer_zone_connections yes)
			)
		)
	)
)
